(kicad_pcb
	(version 20221018)
	(generator pcbnew)
	(general
    (thickness 1.62)
  )
	(paper "A4")
	(title_block
    (title "ECP5 - Datacenter Secure Control Module (DC-SCM)")
    (date "2024-07-01")
    (rev "1.2.1")
		(comment 9 "footprint 50 of 506 (U21), pads 597-701 of 756")
	)
	(layers
    (0 "F.Cu" signal)
    (1 "In1.Cu" power)
    (2 "In2.Cu" signal)
    (3 "In3.Cu" power)
    (4 "In4.Cu" power)
    (5 "In5.Cu" signal)
    (6 "In6.Cu" power)
    (31 "B.Cu" signal)
    (32 "B.Adhes" user "B.Adhesive")
    (33 "F.Adhes" user "F.Adhesive")
    (34 "B.Paste" user)
    (35 "F.Paste" user)
    (36 "B.SilkS" user "B.Silkscreen")
    (37 "F.SilkS" user "F.Silkscreen")
    (38 "B.Mask" user)
    (39 "F.Mask" user)
    (40 "Dwgs.User" user "User.Drawings")
    (41 "Cmts.User" user "User.Comments")
    (42 "Eco1.User" user "User.Eco1")
    (43 "Eco2.User" user "User.Eco2")
    (44 "Edge.Cuts" user)
    (45 "Margin" user)
    (46 "B.CrtYd" user "B.Courtyard")
    (47 "F.CrtYd" user "F.Courtyard")
    (48 "B.Fab" user)
    (49 "F.Fab" user)
  )
	(footprint "antmicro-footprints:BGA-1024-756_27x27mm_Layout32x32_P0.8mm" locked
    (layer "F.Cu")
    (at 104.4 120.55)
    (property "Author" "Antmicro")
    (property "License" "Apache-2.0")
    (property "MPN" "LFE5UM5G-85F-8BG756C")
    (property "Manufacturer" "Lattice Semiconductor")
    (property "Sheetfile" "fpga-power-supply.kicad_sch")
    (property "Sheetname" "FPGA power supply")
    (property "ki_description" "ECP5-5G Field Programmable Gate Array")
    (property "ki_keywords" "SMT, FPGA, IC")
    (attr smd)
    (fp_text reference "U21" (at -12.97 -14.53) (layer "F.SilkS")
        (effects (font (size 0.7 0.7) (thickness 0.127)))
    )
    (fp_text value "ECP5UM5G_85_CABGA756" (at 0 14.5) (layer "F.Fab")
        (effects (font (size 1 1) (thickness 0.15)))
    )
    (pad "R7" smd circle locked (at -7.6 -1.2) (size 0.4 0.4) (layers "F.Cu" "F.Paste" "F.Mask")
      (net 243 "DDR3_A8") (pinfunction "PL47C") (pintype "bidirectional"))
    (pad "R10" smd circle locked (at -5.2 -1.2) (size 0.4 0.4) (layers "F.Cu" "F.Paste" "F.Mask")
      (net 2 "VCC3V3") (pinfunction "VCCIO7") (pintype "passive"))
    (pad "R11" smd circle locked (at -4.4 -1.2) (size 0.4 0.4) (layers "F.Cu" "F.Paste" "F.Mask")
      (net 1 "GND") (pinfunction "GND") (pintype "passive"))
    (pad "R12" smd circle locked (at -3.6 -1.2) (size 0.4 0.4) (layers "F.Cu" "F.Paste" "F.Mask")
      (net 211 "VCC1V2") (pinfunction "VCC") (pintype "passive"))
    (pad "R13" smd circle locked (at -2.8 -1.2) (size 0.4 0.4) (layers "F.Cu" "F.Paste" "F.Mask")
      (net 1 "GND") (pinfunction "GND") (pintype "passive"))
    (pad "R14" smd circle locked (at -2 -1.2) (size 0.4 0.4) (layers "F.Cu" "F.Paste" "F.Mask")
      (net 1 "GND") (pinfunction "GND") (pintype "passive"))
    (pad "R15" smd circle locked (at -1.2 -1.2) (size 0.4 0.4) (layers "F.Cu" "F.Paste" "F.Mask")
      (net 1 "GND") (pinfunction "GND") (pintype "passive"))
    (pad "R16" smd circle locked (at -0.4 -1.2) (size 0.4 0.4) (layers "F.Cu" "F.Paste" "F.Mask")
      (net 1 "GND") (pinfunction "GND") (pintype "passive"))
    (pad "R17" smd circle locked (at 0.4 -1.2) (size 0.4 0.4) (layers "F.Cu" "F.Paste" "F.Mask")
      (net 1 "GND") (pinfunction "GND") (pintype "passive"))
    (pad "R18" smd circle locked (at 1.2 -1.2) (size 0.4 0.4) (layers "F.Cu" "F.Paste" "F.Mask")
      (net 1 "GND") (pinfunction "GND") (pintype "passive"))
    (pad "R19" smd circle locked (at 2 -1.2) (size 0.4 0.4) (layers "F.Cu" "F.Paste" "F.Mask")
      (net 1 "GND") (pinfunction "GND") (pintype "passive"))
    (pad "R20" smd circle locked (at 2.8 -1.2) (size 0.4 0.4) (layers "F.Cu" "F.Paste" "F.Mask")
      (net 1 "GND") (pinfunction "GND") (pintype "passive"))
    (pad "R21" smd circle locked (at 3.6 -1.2) (size 0.4 0.4) (layers "F.Cu" "F.Paste" "F.Mask")
      (net 211 "VCC1V2") (pinfunction "VCC") (pintype "passive"))
    (pad "R22" smd circle locked (at 4.4 -1.2) (size 0.4 0.4) (layers "F.Cu" "F.Paste" "F.Mask")
      (net 1 "GND") (pinfunction "GND") (pintype "passive"))
    (pad "R23" smd circle locked (at 5.2 -1.2) (size 0.4 0.4) (layers "F.Cu" "F.Paste" "F.Mask")
      (net 218 "VCC1V8") (pinfunction "VCCIO2") (pintype "passive"))
    (pad "R26" smd circle locked (at 7.6 -1.2) (size 0.4 0.4) (layers "F.Cu" "F.Paste" "F.Mask")
      (net 321 "ULPI2_CLKO") (pinfunction "PR47C") (pintype "bidirectional"))
    (pad "R27" smd circle locked (at 8.4 -1.2) (size 0.4 0.4) (layers "F.Cu" "F.Paste" "F.Mask")
      (net 123 "PRSNT1_N") (pinfunction "PR50A") (pintype "bidirectional"))
    (pad "R28" smd circle locked (at 9.2 -1.2) (size 0.4 0.4) (layers "F.Cu" "F.Paste" "F.Mask")
      (net 1 "GND") (pinfunction "GND") (pintype "passive"))
    (pad "R29" smd circle locked (at 10 -1.2) (size 0.4 0.4) (layers "F.Cu" "F.Paste" "F.Mask")
      (net 122 "IRQ_N") (pinfunction "PR53A") (pintype "bidirectional"))
    (pad "R30" smd circle locked (at 10.8 -1.2) (size 0.4 0.4) (layers "F.Cu" "F.Paste" "F.Mask")
      (net 754 "unconnected-(U21E-PR59C-PadR30)") (pinfunction "PR59C") (pintype "bidirectional+no_connect"))
    (pad "R31" smd circle locked (at 11.6 -1.2) (size 0.4 0.4) (layers "F.Cu" "F.Paste" "F.Mask")
      (net 1 "GND") (pinfunction "GND") (pintype "passive"))
    (pad "R32" smd circle locked (at 12.4 -1.2) (size 0.4 0.4) (layers "F.Cu" "F.Paste" "F.Mask")
      (net 335 "ULPI1_D7") (pinfunction "PR65A") (pintype "bidirectional"))
    (pad "T1" smd circle locked (at -12.4 -0.4) (size 0.4 0.4) (layers "F.Cu" "F.Paste" "F.Mask")
      (net 755 "unconnected-(U21G-PL68A-PadT1)") (pinfunction "PL68A") (pintype "bidirectional+no_connect"))
    (pad "T2" smd circle locked (at -11.6 -0.4) (size 0.4 0.4) (layers "F.Cu" "F.Paste" "F.Mask")
      (net 263 "DDR3_RESET") (pinfunction "PL65B") (pintype "bidirectional"))
    (pad "T3" smd circle locked (at -10.8 -0.4) (size 0.4 0.4) (layers "F.Cu" "F.Paste" "F.Mask")
      (net 756 "unconnected-(U21G-PL59D-PadT3)") (pinfunction "PL59D") (pintype "bidirectional+no_connect"))
    (pad "T4" smd circle locked (at -10 -0.4) (size 0.4 0.4) (layers "F.Cu" "F.Paste" "F.Mask")
      (net 237 "DDR3_A13") (pinfunction "PL53C") (pintype "bidirectional"))
    (pad "T5" smd circle locked (at -9.2 -0.4) (size 0.4 0.4) (layers "F.Cu" "F.Paste" "F.Mask")
      (net 248 "DDR3_A12") (pinfunction "PL53B") (pintype "bidirectional"))
    (pad "T6" smd circle locked (at -8.4 -0.4) (size 0.4 0.4) (layers "F.Cu" "F.Paste" "F.Mask")
      (net 238 "DDR3_A11") (pinfunction "PL50B") (pintype "bidirectional"))
    (pad "T7" smd circle locked (at -7.6 -0.4) (size 0.4 0.4) (layers "F.Cu" "F.Paste" "F.Mask")
      (net 244 "DDR3_A14") (pinfunction "PL47D") (pintype "bidirectional"))
    (pad "T10" smd circle locked (at -5.2 -0.4) (size 0.4 0.4) (layers "F.Cu" "F.Paste" "F.Mask")
      (net 2 "VCC3V3") (pinfunction "VCCIO7") (pintype "passive"))
    (pad "T11" smd circle locked (at -4.4 -0.4) (size 0.4 0.4) (layers "F.Cu" "F.Paste" "F.Mask")
      (net 1 "GND") (pinfunction "GND") (pintype "passive"))
    (pad "T12" smd circle locked (at -3.6 -0.4) (size 0.4 0.4) (layers "F.Cu" "F.Paste" "F.Mask")
      (net 211 "VCC1V2") (pinfunction "VCC") (pintype "passive"))
    (pad "T13" smd circle locked (at -2.8 -0.4) (size 0.4 0.4) (layers "F.Cu" "F.Paste" "F.Mask")
      (net 1 "GND") (pinfunction "GND") (pintype "passive"))
    (pad "T14" smd circle locked (at -2 -0.4) (size 0.4 0.4) (layers "F.Cu" "F.Paste" "F.Mask")
      (net 1 "GND") (pinfunction "GND") (pintype "passive"))
    (pad "T15" smd circle locked (at -1.2 -0.4) (size 0.4 0.4) (layers "F.Cu" "F.Paste" "F.Mask")
      (net 1 "GND") (pinfunction "GND") (pintype "passive"))
    (pad "T16" smd circle locked (at -0.4 -0.4) (size 0.4 0.4) (layers "F.Cu" "F.Paste" "F.Mask")
      (net 1 "GND") (pinfunction "GND") (pintype "passive"))
    (pad "T17" smd circle locked (at 0.4 -0.4) (size 0.4 0.4) (layers "F.Cu" "F.Paste" "F.Mask")
      (net 1 "GND") (pinfunction "GND") (pintype "passive"))
    (pad "T18" smd circle locked (at 1.2 -0.4) (size 0.4 0.4) (layers "F.Cu" "F.Paste" "F.Mask")
      (net 1 "GND") (pinfunction "GND") (pintype "passive"))
    (pad "T19" smd circle locked (at 2 -0.4) (size 0.4 0.4) (layers "F.Cu" "F.Paste" "F.Mask")
      (net 1 "GND") (pinfunction "GND") (pintype "passive"))
    (pad "T20" smd circle locked (at 2.8 -0.4) (size 0.4 0.4) (layers "F.Cu" "F.Paste" "F.Mask")
      (net 1 "GND") (pinfunction "GND") (pintype "passive"))
    (pad "T21" smd circle locked (at 3.6 -0.4) (size 0.4 0.4) (layers "F.Cu" "F.Paste" "F.Mask")
      (net 211 "VCC1V2") (pinfunction "VCC") (pintype "passive"))
    (pad "T22" smd circle locked (at 4.4 -0.4) (size 0.4 0.4) (layers "F.Cu" "F.Paste" "F.Mask")
      (net 1 "GND") (pinfunction "GND") (pintype "passive"))
    (pad "T23" smd circle locked (at 5.2 -0.4) (size 0.4 0.4) (layers "F.Cu" "F.Paste" "F.Mask")
      (net 218 "VCC1V8") (pinfunction "VCCIO2") (pintype "passive"))
    (pad "T26" smd circle locked (at 7.6 -0.4) (size 0.4 0.4) (layers "F.Cu" "F.Paste" "F.Mask")
      (net 757 "unconnected-(U21E-PR47D-PadT26)") (pinfunction "PR47D") (pintype "bidirectional+no_connect"))
    (pad "T27" smd circle locked (at 8.4 -0.4) (size 0.4 0.4) (layers "F.Cu" "F.Paste" "F.Mask")
      (net 115 "DBP_PREQ_N") (pinfunction "PR50B") (pintype "bidirectional"))
    (pad "T28" smd circle locked (at 9.2 -0.4) (size 0.4 0.4) (layers "F.Cu" "F.Paste" "F.Mask")
      (net 121 "SPARE0") (pinfunction "PR53B") (pintype "bidirectional"))
    (pad "T29" smd circle locked (at 10 -0.4) (size 0.4 0.4) (layers "F.Cu" "F.Paste" "F.Mask")
      (net 120 "CHASI#") (pinfunction "PR53C") (pintype "bidirectional"))
    (pad "T30" smd circle locked (at 10.8 -0.4) (size 0.4 0.4) (layers "F.Cu" "F.Paste" "F.Mask")
      (net 758 "unconnected-(U21E-PR59D-PadT30)") (pinfunction "PR59D") (pintype "bidirectional+no_connect"))
    (pad "T31" smd circle locked (at 11.6 -0.4) (size 0.4 0.4) (layers "F.Cu" "F.Paste" "F.Mask")
      (net 337 "ULPI1_D5") (pinfunction "PR65B") (pintype "bidirectional"))
    (pad "T32" smd circle locked (at 12.4 -0.4) (size 0.4 0.4) (layers "F.Cu" "F.Paste" "F.Mask")
      (net 336 "ULPI1_D6") (pinfunction "PR68A") (pintype "bidirectional"))
    (pad "U1" smd circle locked (at -12.4 0.4) (size 0.4 0.4) (layers "F.Cu" "F.Paste" "F.Mask")
      (net 759 "unconnected-(U21G-PL68B-PadU1)") (pinfunction "PL68B") (pintype "bidirectional+no_connect"))
    (pad "U2" smd circle locked (at -11.6 0.4) (size 0.4 0.4) (layers "F.Cu" "F.Paste" "F.Mask")
      (net 760 "unconnected-(U21G-PL62C-PadU2)") (pinfunction "PL62C") (pintype "bidirectional+no_connect"))
    (pad "U3" smd circle locked (at -10.8 0.4) (size 0.4 0.4) (layers "F.Cu" "F.Paste" "F.Mask")
      (net 761 "unconnected-(U21G-PL62D-PadU3)") (pinfunction "PL62D") (pintype "bidirectional+no_connect"))
    (pad "U4" smd circle locked (at -10 0.4) (size 0.4 0.4) (layers "F.Cu" "F.Paste" "F.Mask")
      (net 250 "DDR3_A10") (pinfunction "PL56A") (pintype "bidirectional"))
    (pad "U5" smd circle locked (at -9.2 0.4) (size 0.4 0.4) (layers "F.Cu" "F.Paste" "F.Mask")
      (net 240 "DDR3_A7") (pinfunction "PL53D") (pintype "bidirectional"))
    (pad "U6" smd circle locked (at -8.4 0.4) (size 0.4 0.4) (layers "F.Cu" "F.Paste" "F.Mask")
      (net 242 "DDR3_A6") (pinfunction "PL50C") (pintype "bidirectional"))
    (pad "U7" smd circle locked (at -7.6 0.4) (size 0.4 0.4) (layers "F.Cu" "F.Paste" "F.Mask")
      (net 241 "DDR3_A2") (pinfunction "PL50D") (pintype "bidirectional"))
    (pad "U10" smd circle locked (at -5.2 0.4) (size 0.4 0.4) (layers "F.Cu" "F.Paste" "F.Mask")
      (net 3 "VCC1V35") (pinfunction "VCCIO6") (pintype "passive"))
    (pad "U11" smd circle locked (at -4.4 0.4) (size 0.4 0.4) (layers "F.Cu" "F.Paste" "F.Mask")
      (net 1 "GND") (pinfunction "GND") (pintype "passive"))
    (pad "U12" smd circle locked (at -3.6 0.4) (size 0.4 0.4) (layers "F.Cu" "F.Paste" "F.Mask")
      (net 211 "VCC1V2") (pinfunction "VCC") (pintype "passive"))
    (pad "U13" smd circle locked (at -2.8 0.4) (size 0.4 0.4) (layers "F.Cu" "F.Paste" "F.Mask")
      (net 1 "GND") (pinfunction "GND") (pintype "passive"))
    (pad "U14" smd circle locked (at -2 0.4) (size 0.4 0.4) (layers "F.Cu" "F.Paste" "F.Mask")
      (net 1 "GND") (pinfunction "GND") (pintype "passive"))
    (pad "U15" smd circle locked (at -1.2 0.4) (size 0.4 0.4) (layers "F.Cu" "F.Paste" "F.Mask")
      (net 1 "GND") (pinfunction "GND") (pintype "passive"))
    (pad "U16" smd circle locked (at -0.4 0.4) (size 0.4 0.4) (layers "F.Cu" "F.Paste" "F.Mask")
      (net 1 "GND") (pinfunction "GND") (pintype "passive"))
    (pad "U17" smd circle locked (at 0.4 0.4) (size 0.4 0.4) (layers "F.Cu" "F.Paste" "F.Mask")
      (net 1 "GND") (pinfunction "GND") (pintype "passive"))
    (pad "U18" smd circle locked (at 1.2 0.4) (size 0.4 0.4) (layers "F.Cu" "F.Paste" "F.Mask")
      (net 1 "GND") (pinfunction "GND") (pintype "passive"))
    (pad "U19" smd circle locked (at 2 0.4) (size 0.4 0.4) (layers "F.Cu" "F.Paste" "F.Mask")
      (net 1 "GND") (pinfunction "GND") (pintype "passive"))
    (pad "U20" smd circle locked (at 2.8 0.4) (size 0.4 0.4) (layers "F.Cu" "F.Paste" "F.Mask")
      (net 1 "GND") (pinfunction "GND") (pintype "passive"))
    (pad "U21" smd circle locked (at 3.6 0.4) (size 0.4 0.4) (layers "F.Cu" "F.Paste" "F.Mask")
      (net 211 "VCC1V2") (pinfunction "VCC") (pintype "passive"))
    (pad "U22" smd circle locked (at 4.4 0.4) (size 0.4 0.4) (layers "F.Cu" "F.Paste" "F.Mask")
      (net 1 "GND") (pinfunction "GND") (pintype "passive"))
    (pad "U23" smd circle locked (at 5.2 0.4) (size 0.4 0.4) (layers "F.Cu" "F.Paste" "F.Mask")
      (net 2 "VCC3V3") (pinfunction "VCCIO3") (pintype "passive"))
    (pad "U26" smd circle locked (at 7.6 0.4) (size 0.4 0.4) (layers "F.Cu" "F.Paste" "F.Mask")
      (net 113 "SYS_PWRBTN_N") (pinfunction "PR50D") (pintype "bidirectional"))
    (pad "U27" smd circle locked (at 8.4 0.4) (size 0.4 0.4) (layers "F.Cu" "F.Paste" "F.Mask")
      (net 114 "SYS_PWROK") (pinfunction "PR50C") (pintype "bidirectional"))
    (pad "U28" smd circle locked (at 9.2 0.4) (size 0.4 0.4) (layers "F.Cu" "F.Paste" "F.Mask")
      (net 119 "RoT_CPU_RST_N") (pinfunction "PR53D") (pintype "bidirectional"))
    (pad "U29" smd circle locked (at 10 0.4) (size 0.4 0.4) (layers "F.Cu" "F.Paste" "F.Mask")
      (net 118 "SPARE1") (pinfunction "PR56A") (pintype "bidirectional"))
    (pad "U30" smd circle locked (at 10.8 0.4) (size 0.4 0.4) (layers "F.Cu" "F.Paste" "F.Mask")
      (net 762 "unconnected-(U21E-PR62D-PadU30)") (pinfunction "PR62D") (pintype "bidirectional+no_connect"))
    (pad "U31" smd circle locked (at 11.6 0.4) (size 0.4 0.4) (layers "F.Cu" "F.Paste" "F.Mask")
      (net 339 "ULPI1_D3") (pinfunction "PR62C") (pintype "bidirectional"))
    (pad "U32" smd circle locked (at 12.4 0.4) (size 0.4 0.4) (layers "F.Cu" "F.Paste" "F.Mask")
      (net 338 "ULPI1_D4") (pinfunction "PR68B") (pintype "bidirectional"))
    (pad "V1" smd circle locked (at -12.4 1.2) (size 0.4 0.4) (layers "F.Cu" "F.Paste" "F.Mask")
      (net 763 "unconnected-(U21G-PL68C-PadV1)") (pinfunction "PL68C") (pintype "bidirectional+no_connect"))
    (pad "V2" smd circle locked (at -11.6 1.2) (size 0.4 0.4) (layers "F.Cu" "F.Paste" "F.Mask")
      (net 1 "GND") (pinfunction "GND") (pintype "passive"))
    (pad "V3" smd circle locked (at -10.8 1.2) (size 0.4 0.4) (layers "F.Cu" "F.Paste" "F.Mask")
      (net 764 "unconnected-(U21A-NC-PadV3)") (pinfunction "NC") (pintype "no_connect"))
    (pad "V4" smd circle locked (at -10 1.2) (size 0.4 0.4) (layers "F.Cu" "F.Paste" "F.Mask")
      (net 217 "DDR3_VREF") (pinfunction "PL56B") (pintype "bidirectional"))
    (pad "V5" smd circle locked (at -9.2 1.2) (size 0.4 0.4) (layers "F.Cu" "F.Paste" "F.Mask")
      (net 1 "GND") (pinfunction "GND") (pintype "passive"))
    (pad "V6" smd circle locked (at -8.4 1.2) (size 0.4 0.4) (layers "F.Cu" "F.Paste" "F.Mask")
      (net 249 "DDR3_BA1") (pinfunction "PL56C") (pintype "bidirectional"))
    (pad "V7" smd circle locked (at -7.6 1.2) (size 0.4 0.4) (layers "F.Cu" "F.Paste" "F.Mask")
      (net 247 "DDR3_A1") (pinfunction "PL56D") (pintype "bidirectional"))
    (pad "V10" smd circle locked (at -5.2 1.2) (size 0.4 0.4) (layers "F.Cu" "F.Paste" "F.Mask")
      (net 3 "VCC1V35") (pinfunction "VCCIO6") (pintype "passive"))
    (pad "V11" smd circle locked (at -4.4 1.2) (size 0.4 0.4) (layers "F.Cu" "F.Paste" "F.Mask")
      (net 1 "GND") (pinfunction "GND") (pintype "passive"))
    (pad "V12" smd circle locked (at -3.6 1.2) (size 0.4 0.4) (layers "F.Cu" "F.Paste" "F.Mask")
      (net 211 "VCC1V2") (pinfunction "VCC") (pintype "passive"))
    (pad "V13" smd circle locked (at -2.8 1.2) (size 0.4 0.4) (layers "F.Cu" "F.Paste" "F.Mask")
      (net 1 "GND") (pinfunction "GND") (pintype "passive"))
    (pad "V14" smd circle locked (at -2 1.2) (size 0.4 0.4) (layers "F.Cu" "F.Paste" "F.Mask")
      (net 1 "GND") (pinfunction "GND") (pintype "passive"))
    (pad "V15" smd circle locked (at -1.2 1.2) (size 0.4 0.4) (layers "F.Cu" "F.Paste" "F.Mask")
      (net 1 "GND") (pinfunction "GND") (pintype "passive"))
    (pad "V16" smd circle locked (at -0.4 1.2) (size 0.4 0.4) (layers "F.Cu" "F.Paste" "F.Mask")
      (net 1 "GND") (pinfunction "GND") (pintype "passive"))
    (pad "V17" smd circle locked (at 0.4 1.2) (size 0.4 0.4) (layers "F.Cu" "F.Paste" "F.Mask")
      (net 1 "GND") (pinfunction "GND") (pintype "passive"))
    (pad "V18" smd circle locked (at 1.2 1.2) (size 0.4 0.4) (layers "F.Cu" "F.Paste" "F.Mask")
      (net 1 "GND") (pinfunction "GND") (pintype "passive"))
    (pad "V19" smd circle locked (at 2 1.2) (size 0.4 0.4) (layers "F.Cu" "F.Paste" "F.Mask")
      (net 1 "GND") (pinfunction "GND") (pintype "passive"))
    (pad "V20" smd circle locked (at 2.8 1.2) (size 0.4 0.4) (layers "F.Cu" "F.Paste" "F.Mask")
      (net 1 "GND") (pinfunction "GND") (pintype "passive"))
    (pad "V21" smd circle locked (at 3.6 1.2) (size 0.4 0.4) (layers "F.Cu" "F.Paste" "F.Mask")
      (net 211 "VCC1V2") (pinfunction "VCC") (pintype "passive"))
    (pad "V22" smd circle locked (at 4.4 1.2) (size 0.4 0.4) (layers "F.Cu" "F.Paste" "F.Mask")
      (net 1 "GND") (pinfunction "GND") (pintype "passive"))
    (pad "V23" smd circle locked (at 5.2 1.2) (size 0.4 0.4) (layers "F.Cu" "F.Paste" "F.Mask")
      (net 2 "VCC3V3") (pinfunction "VCCIO3") (pintype "passive"))
    (pad "V26" smd circle locked (at 7.6 1.2) (size 0.4 0.4) (layers "F.Cu" "F.Paste" "F.Mask")
      (net 765 "unconnected-(U21E-PR56D-PadV26)") (pinfunction "PR56D") (pintype "bidirectional+no_connect"))
    (pad "V27" smd circle locked (at 8.4 1.2) (size 0.4 0.4) (layers "F.Cu" "F.Paste" "F.Mask")
      (net 766 "unconnected-(U21E-PR56C-PadV27)") (pinfunction "PR56C") (pintype "bidirectional+no_connect"))
    (pad "V28" smd circle locked (at 9.2 1.2) (size 0.4 0.4) (layers "F.Cu" "F.Paste" "F.Mask")
      (net 1 "GND") (pinfunction "GND") (pintype "passive"))
    (pad "V29" smd circle locked (at 10 1.2) (size 0.4 0.4) (layers "F.Cu" "F.Paste" "F.Mask")
      (net 117 "RST_PLTRST_BUF_N") (pinfunction "PR56B") (pintype "bidirectional"))
    (pad "V30" smd circle locked (at 10.8 1.2) (size 0.4 0.4) (layers "F.Cu" "F.Paste" "F.Mask")
      (net 767 "unconnected-(U21A-NC-PadV30)") (pinfunction "NC") (pintype "no_connect"))
    (pad "V31" smd circle locked (at 11.6 1.2) (size 0.4 0.4) (layers "F.Cu" "F.Paste" "F.Mask")
      (net 1 "GND") (pinfunction "GND") (pintype "passive"))
  )
)
